# S9S_MB_2U (Grand Teton) — schematic netlist excerpt (pin names and nets, part order shuffled) for the footprints in the layout excerpt that follows; sources: Cadence DE-HDL packaged netlist, KiCad conversion of 03242023_DA0F0TMBIJ0_F0T_Motherboard_J_brd_V01_OCP.brd

PC485_P1_8  Q_CAP  1UF 16V 10% X6S  pkg C0402  page 288 : A = SW_P12V_PVCCIN_CPU1_FLT ; B = GND
R2675  Q_RES  33.2 1% CHIP  pkg 0402LF  page 234 : A = I3C_BMC_SWB_BUF_R_SCL ; B = I3C_BMC_SWB_BUF_SCL

(kicad_pcb
	(version 20260206)
	(generator "pcbnew")
	(generator_version "10.0")
	(general
		(thickness 1.6)
		(legacy_teardrops no)
	)
	(paper "A4")
	(title_block
		(title "03242023_DA0F0TMBIJ0_F0T_Motherboard_J_brd_V01_OCP.brd")
		(comment 1 "Grand Teton / footprints 1258-1259 of 6105")
	)
	(layers
		(0 "F.Cu" signal "TOP")
		(4 "In1.Cu" signal "GND")
		(6 "In2.Cu" signal "IN1")
		(8 "In3.Cu" signal "GND1")
		(10 "In4.Cu" signal "IN2")
		(12 "In5.Cu" signal "GND2")
		(14 "In6.Cu" signal "IN3")
		(16 "In7.Cu" signal "GND3")
		(18 "In8.Cu" signal "VCC")
		(20 "In9.Cu" signal "VCC1")
		(22 "In10.Cu" signal "GND4")
		(24 "In11.Cu" signal "IN4")
		(26 "In12.Cu" signal "GND5")
		(28 "In13.Cu" signal "IN5")
		(30 "In14.Cu" signal "GND6")
		(32 "In15.Cu" signal "IN6")
		(34 "In16.Cu" signal "GND7")
		(2 "B.Cu" signal "BOTTOM")
		(9 "F.Adhes" user "F.Adhesive")
		(11 "B.Adhes" user "B.Adhesive")
		(13 "F.Paste" user "Package Geometry/Pastemask Top")
		(15 "B.Paste" user "Package Geometry/Pastemask Bottom")
		(5 "F.SilkS" user "Ref Des/Silkscreen Top")
		(7 "B.SilkS" user "Ref Des/Silkscreen Bottom")
		(1 "F.Mask" user "Board Geometry/Soldermask Top")
		(3 "B.Mask" user "Board Geometry/Soldermask Bottom")
		(17 "Dwgs.User" user "User.Drawings")
		(19 "Cmts.User" user "User.Comments")
		(21 "Eco1.User" user "User.Eco1")
		(23 "Eco2.User" user "User.Eco2")
		(25 "Edge.Cuts" user "Board Geometry/Outline")
		(27 "Margin" user)
		(31 "F.CrtYd" user "Package Geometry/Place Bound Top")
		(29 "B.CrtYd" user "Package Geometry/Place Bound Bottom")
		(35 "F.Fab" user "Ref Des/Assembly Top")
		(33 "B.Fab" user "Ref Des/Assembly Bottom")
	)
	(footprint ""
		(layer "F.Cu")
		(at 354.687632 -398.789398 180)
		(property "Reference" "R2675"
			(at 0 0 180)
			(layer "F.SilkS")
			(hide yes)
			(effects
				(font
					(size 1.27 1.27)
				)
			)
		)
		(property "Value" ""
			(at 0 0 180)
			(layer "F.Fab")
			(effects
				(font
					(size 1.27 1.27)
				)
			)
		)
		(duplicate_pad_numbers_are_jumpers no)
		(fp_line
			(start 0.7874 0.4064)
			(end -0.7874 0.4064)
			(stroke
				(width 0.1524)
				(type default)
			)
			(layer "F.SilkS")
		)
		(fp_line
			(start 0.7874 -0.4064)
			(end 0.7874 0.4064)
			(stroke
				(width 0.1524)
				(type default)
			)
			(layer "F.SilkS")
		)
		(fp_line
			(start -0.7874 0.4064)
			(end -0.7874 -0.4064)
			(stroke
				(width 0.1524)
				(type default)
			)
			(layer "F.SilkS")
		)
		(fp_line
			(start -0.7874 -0.4064)
			(end 0.7874 -0.4064)
			(stroke
				(width 0.1524)
				(type default)
			)
			(layer "F.SilkS")
		)
		(fp_line
			(start 0.67945 0.3048)
			(end 0.120396 0.3048)
			(stroke
				(width 0.1)
				(type default)
			)
			(layer "F.Fab")
		)
		(fp_line
			(start 0.67945 -0.3048)
			(end 0.67945 0.3048)
			(stroke
				(width 0.1)
				(type default)
			)
			(layer "F.Fab")
		)
		(fp_line
			(start 0.12065 -0.2794)
			(end 0.12065 -0.3048)
			(stroke
				(width 0.1)
				(type default)
			)
			(layer "F.Fab")
		)
		(fp_line
			(start 0.12065 -0.3048)
			(end 0.67945 -0.3048)
			(stroke
				(width 0.1)
				(type default)
			)
			(layer "F.Fab")
		)
		(fp_line
			(start 0.120396 0.3048)
			(end 0.120396 0.2794)
			(stroke
				(width 0.1)
				(type default)
			)
			(layer "F.Fab")
		)
		(fp_line
			(start 0.120396 0.2794)
			(end -0.12065 0.2794)
			(stroke
				(width 0.1)
				(type default)
			)
			(layer "F.Fab")
		)
		(fp_line
			(start -0.12065 0.3048)
			(end -0.67945 0.3048)
			(stroke
				(width 0.1)
				(type default)
			)
			(layer "F.Fab")
		)
		(fp_line
			(start -0.12065 0.2794)
			(end -0.12065 0.3048)
			(stroke
				(width 0.1)
				(type default)
			)
			(layer "F.Fab")
		)
		(fp_line
			(start -0.12065 -0.2794)
			(end 0.12065 -0.2794)
			(stroke
				(width 0.1)
				(type default)
			)
			(layer "F.Fab")
		)
		(fp_line
			(start -0.12065 -0.305054)
			(end -0.12065 -0.2794)
			(stroke
				(width 0.1)
				(type default)
			)
			(layer "F.Fab")
		)
		(fp_line
			(start -0.67945 0.3048)
			(end -0.67945 -0.305054)
			(stroke
				(width 0.1)
				(type default)
			)
			(layer "F.Fab")
		)
		(fp_line
			(start -0.67945 -0.305054)
			(end -0.12065 -0.305054)
			(stroke
				(width 0.1)
				(type default)
			)
			(layer "F.Fab")
		)
		(pad "1" smd circle
			(at -0.40005 0 180)
			(size 0 0)
			(layers "F.Cu" "F.Mask" "F.Paste")
			(net "I3C_BMC_SWB_BUF_R_SCL")
		)
		(pad "2" smd circle
			(at 0.40005 0 180)
			(size 0 0)
			(layers "F.Cu" "F.Mask" "F.Paste")
			(net "I3C_BMC_SWB_BUF_SCL")
		)
	)
	(footprint ""
		(layer "F.Cu")
		(at 141.372844 -343.018872 -90)
		(property "Reference" "PC485_P1_8"
			(at 0 0 270)
			(layer "F.SilkS")
			(hide yes)
			(effects
				(font
					(size 1.27 1.27)
				)
			)
		)
		(property "Value" ""
			(at 0 0 270)
			(layer "F.Fab")
			(effects
				(font
					(size 1.27 1.27)
				)
			)
		)
		(duplicate_pad_numbers_are_jumpers no)
		(fp_line
			(start -0.7874 0.4064)
			(end -0.7874 -0.4064)
			(stroke
				(width 0.1524)
				(type default)
			)
			(layer "F.SilkS")
		)
		(fp_line
			(start 0.7874 0.4064)
			(end -0.7874 0.4064)
			(stroke
				(width 0.1524)
				(type default)
			)
			(layer "F.SilkS")
		)
		(fp_line
			(start -0.7874 -0.4064)
			(end 0.7874 -0.4064)
			(stroke
				(width 0.1524)
				(type default)
			)
			(layer "F.SilkS")
		)
		(fp_line
			(start 0.7874 -0.4064)
			(end 0.7874 0.4064)
			(stroke
				(width 0.1524)
				(type default)
			)
			(layer "F.SilkS")
		)
		(fp_line
			(start -0.67945 0.3048)
			(end -0.67945 -0.305054)
			(stroke
				(width 0.1)
				(type default)
			)
			(layer "F.Fab")
		)
		(fp_line
			(start -0.12065 0.3048)
			(end -0.67945 0.3048)
			(stroke
				(width 0.1)
				(type default)
			)
			(layer "F.Fab")
		)
		(fp_line
			(start 0.120396 0.3048)
			(end 0.120396 0.2794)
			(stroke
				(width 0.1)
				(type default)
			)
			(layer "F.Fab")
		)
		(fp_line
			(start 0.67945 0.3048)
			(end 0.120396 0.3048)
			(stroke
				(width 0.1)
				(type default)
			)
			(layer "F.Fab")
		)
		(fp_line
			(start -0.12065 0.2794)
			(end -0.12065 0.3048)
			(stroke
				(width 0.1)
				(type default)
			)
			(layer "F.Fab")
		)
		(fp_line
			(start 0.120396 0.2794)
			(end -0.12065 0.2794)
			(stroke
				(width 0.1)
				(type default)
			)
			(layer "F.Fab")
		)
		(fp_line
			(start -0.12065 -0.2794)
			(end 0.12065 -0.2794)
			(stroke
				(width 0.1)
				(type default)
			)
			(layer "F.Fab")
		)
		(fp_line
			(start 0.12065 -0.2794)
			(end 0.12065 -0.3048)
			(stroke
				(width 0.1)
				(type default)
			)
			(layer "F.Fab")
		)
		(fp_line
			(start 0.12065 -0.3048)
			(end 0.67945 -0.3048)
			(stroke
				(width 0.1)
				(type default)
			)
			(layer "F.Fab")
		)
		(fp_line
			(start 0.67945 -0.3048)
			(end 0.67945 0.3048)
			(stroke
				(width 0.1)
				(type default)
			)
			(layer "F.Fab")
		)
		(fp_line
			(start -0.67945 -0.305054)
			(end -0.12065 -0.305054)
			(stroke
				(width 0.1)
				(type default)
			)
			(layer "F.Fab")
		)
		(fp_line
			(start -0.12065 -0.305054)
			(end -0.12065 -0.2794)
			(stroke
				(width 0.1)
				(type default)
			)
			(layer "F.Fab")
		)
		(pad "1" smd circle
			(at -0.40005 0 270)
			(size 0 0)
			(layers "F.Cu" "F.Mask" "F.Paste")
			(net "SW_P12V_PVCCIN_CPU1_FLT")
		)
		(pad "2" smd circle
			(at 0.40005 0 270)
			(size 0 0)
			(layers "F.Cu" "F.Mask" "F.Paste")
			(net "GND")
		)
	)
)
